(kicad_pcb
	(version 20260206)
	(generator "pcbnew")
	(generator_version "10.0")
	(general
		(thickness 1.6)
		(legacy_teardrops no)
	)
	(paper "A4")
	(title_block
		(title "timecard-production-celestica-r4006 — R4006-B0001-02_R01.brd")
		(comment 1 "Time Appliance Project (Time Card) / footprints 198-198 of 1113")
	)
	(layers
		(0 "F.Cu" signal "TOP")
		(4 "In1.Cu" signal "L02_GND1")
		(6 "In2.Cu" signal "L03_SIG1")
		(8 "In3.Cu" signal "L04_GND2")
		(10 "In4.Cu" signal "L05_VCC1")
		(12 "In5.Cu" signal "L06_VCC2")
		(14 "In6.Cu" signal "L07_GND3")
		(16 "In7.Cu" signal "L08_SIG2")
		(18 "In8.Cu" signal "L09_GND4")
		(2 "B.Cu" signal "BOTTOM")
		(9 "F.Adhes" user "F.Adhesive")
		(11 "B.Adhes" user "B.Adhesive")
		(13 "F.Paste" user "Package Geometry/Pastemask Top")
		(15 "B.Paste" user "Package Geometry/Pastemask Bottom")
		(5 "F.SilkS" user "Ref Des/Silkscreen Top")
		(7 "B.SilkS" user "Ref Des/Silkscreen Bottom")
		(1 "F.Mask" user "Board Geometry/Soldermask Top")
		(3 "B.Mask" user "Board Geometry/Soldermask Bottom")
		(17 "Dwgs.User" user "User.Drawings")
		(19 "Cmts.User" user "User.Comments")
		(21 "Eco1.User" user "User.Eco1")
		(23 "Eco2.User" user "User.Eco2")
		(25 "Edge.Cuts" user "Board Geometry/Outline")
		(27 "Margin" user)
		(31 "F.CrtYd" user "Package Geometry/Place Bound Top")
		(29 "B.CrtYd" user "Package Geometry/Place Bound Bottom")
		(35 "F.Fab" user "Ref Des/Assembly Top")
		(33 "B.Fab" user "Ref Des/Assembly Bottom")
	)
	(footprint ""
		(layer "F.Cu")
		(at 124.587 -52.578 180)
		(property "Reference" "R356"
			(at -3.175 -0.16637 0)
			(unlocked yes)
			(layer "F.SilkS")
			(effects
				(font
					(size 0.7874 0.5842)
					(thickness 0.1524)
				)
			)
		)
		(property "Value" "VAL*"
			(at 0.02032 2.13233 180)
			(unlocked yes)
			(layer "F.Fab")
			(hide yes)
			(effects
				(font
					(size 0.7874 0.5842)
					(thickness 0.1524)
				)
			)
		)
		(property "Tolerance" "TOL*"
			(at 0.044704 3.05435 180)
			(unlocked yes)
			(layer "Cmts.User")
			(hide yes)
			(effects
				(font
					(size 0.7874 0.5842)
					(thickness 0.1524)
				)
			)
		)
		(property "User Part Number" "PARTNUM*"
			(at 0.02032 4.024884 180)
			(unlocked yes)
			(layer "Cmts.User")
			(hide yes)
			(effects
				(font
					(size 0.7874 0.5842)
					(thickness 0.1524)
				)
			)
		)
		(property "Device Type" "RESISTOR-G155-100R0-J0,0OHM,-"
			(at 0.008382 1.210564 180)
			(unlocked yes)
			(layer "F.Fab")
			(hide yes)
			(effects
				(font
					(size 0.7874 0.5842)
					(thickness 0.1524)
				)
			)
		)
		(duplicate_pad_numbers_are_jumpers no)
		(fp_line
			(start 1.143 0.5588)
			(end 1.143 -0.5588)
			(stroke
				(width 0.1)
				(type default)
			)
			(layer "F.SilkS")
		)
		(fp_line
			(start 1.143 -0.5588)
			(end -1.143 -0.5588)
			(stroke
				(width 0.1)
				(type default)
			)
			(layer "F.SilkS")
		)
		(fp_line
			(start -1.143 0.5588)
			(end 1.143 0.5588)
			(stroke
				(width 0.1)
				(type default)
			)
			(layer "F.SilkS")
		)
		(fp_line
			(start -1.143 -0.5588)
			(end -1.143 0.5588)
			(stroke
				(width 0.1)
				(type default)
			)
			(layer "F.SilkS")
		)
		(fp_poly
			(pts
				(xy -1.143 0.5588) (xy 1.143 0.5588) (xy 1.143 -0.5588) (xy -1.143 -0.5588)
			)
			(stroke
				(width 0)
				(type default)
			)
			(fill no)
			(layer "F.CrtYd")
		)
		(fp_line
			(start 0.508 0.3048)
			(end 0.508 -0.3048)
			(stroke
				(width 0.1)
				(type default)
			)
			(layer "F.Fab")
		)
		(fp_line
			(start 0.508 -0.3048)
			(end -0.508 -0.3048)
			(stroke
				(width 0.1)
				(type default)
			)
			(layer "F.Fab")
		)
		(fp_line
			(start -0.508 0.3048)
			(end 0.508 0.3048)
			(stroke
				(width 0.1)
				(type default)
			)
			(layer "F.Fab")
		)
		(fp_line
			(start -0.508 -0.3048)
			(end -0.508 0.3048)
			(stroke
				(width 0.1)
				(type default)
			)
			(layer "F.Fab")
		)
		(pad "1" smd rect
			(at -0.5334 0 180)
			(size 0.7112 0.6096)
			(layers "F.Cu" "F.Mask" "F.Paste")
			(net "BF_PCIE_PERST_N")
		)
		(pad "2" smd rect
			(at 0.5334 0 180)
			(size 0.7112 0.6096)
			(layers "F.Cu" "F.Mask" "F.Paste")
			(net "FPGA_PROGRAM_N")
		)
		(zone
			(layer "F.Cu")
			(hatch none 0.5)
			(connect_pads
				(clearance 0)
			)
			(min_thickness 0.25)
			(keepout
				(tracks not_allowed)
				(vias allowed)
				(pads allowed)
				(copperpour not_allowed)
				(footprints allowed)
			)
			(placement
				(enabled no)
				(sheetname "")
			)
			(fill
				(thermal_gap 0.5)
				(thermal_bridge_width 0.5)
				(island_removal_mode 0)
			)
			(polygon
				(pts
					(xy 124.6632 -52.8828) (xy 124.5108 -52.8828) (xy 124.5108 -52.2732) (xy 124.6632 -52.2732)
				)
			)
		)
		(zone
			(layer "F.Cu")
			(hatch none 0.5)
			(connect_pads
				(clearance 0)
			)
			(min_thickness 0.25)
			(keepout
				(tracks allowed)
				(vias not_allowed)
				(pads allowed)
				(copperpour not_allowed)
				(footprints allowed)
			)
			(placement
				(enabled no)
				(sheetname "")
			)
			(fill
				(thermal_gap 0.5)
				(thermal_bridge_width 0.5)
				(island_removal_mode 0)
			)
			(polygon
				(pts
					(xy 124.6632 -52.8828) (xy 124.5108 -52.8828) (xy 124.5108 -52.2732) (xy 124.6632 -52.2732)
				)
			)
		)
	)
)
